# T6G (Grand Teton) — schematic netlist excerpt (pin names and nets, part order shuffled) for the footprints in the layout excerpt that follows; sources: Cadence DE-HDL packaged netlist, KiCad conversion of 04192023_DAF0TMB3IC0_F0TG_MB_C_brd_V02_OCP.brd

U21  M24M02DRMN6TP  M24M02-DRMN6TP IC  pkg SOIC8XH  page 355
  DU1  = NC
  DU2  = NC
  E2  = U21_E2
  VSS  = GND
  SDA  = SMB_RT_CPU1_P3_ROM_SDA
  SCL  = SMB_RT_CPU1_P3_ROM_SCL
  WC_N  = GND
  VCC  = P1V8_CPU1_RT_1D

R1138  Q_RES  10K 1% CHIP  pkg 0402LF  page 133 : A = P3V3_AUX ; B = CLK_50M_EN
H104  HOLE  EMPTY  pkg TH  page 230 : \1\ = GND

(kicad_pcb
	(version 20260206)
	(generator "pcbnew")
	(generator_version "10.0")
	(general
		(thickness 1.6)
		(legacy_teardrops no)
	)
	(paper "A4")
	(title_block
		(title "04192023_DAF0TMB3IC0_F0TG_MB_C_brd_V02_OCP.brd")
		(comment 1 "Grand Teton / footprints 2065-2067 of 8354")
	)
	(layers
		(0 "F.Cu" signal "TOP")
		(4 "In1.Cu" signal "GND")
		(6 "In2.Cu" signal "IN1")
		(8 "In3.Cu" signal "GND1")
		(10 "In4.Cu" signal "IN2")
		(12 "In5.Cu" signal "GND2")
		(14 "In6.Cu" signal "IN3")
		(16 "In7.Cu" signal "GND3")
		(18 "In8.Cu" signal "VCC")
		(20 "In9.Cu" signal "VCC1")
		(22 "In10.Cu" signal "GND4")
		(24 "In11.Cu" signal "IN4")
		(26 "In12.Cu" signal "GND5")
		(28 "In13.Cu" signal "IN5")
		(30 "In14.Cu" signal "GND6")
		(32 "In15.Cu" signal "IN6")
		(34 "In16.Cu" signal "GND7")
		(2 "B.Cu" signal "BOTTOM")
		(9 "F.Adhes" user "F.Adhesive")
		(11 "B.Adhes" user "B.Adhesive")
		(13 "F.Paste" user "Package Geometry/Pastemask Top")
		(15 "B.Paste" user "Package Geometry/Pastemask Bottom")
		(5 "F.SilkS" user "Ref Des/Silkscreen Top")
		(7 "B.SilkS" user "Ref Des/Silkscreen Bottom")
		(1 "F.Mask" user "Board Geometry/Soldermask Top")
		(3 "B.Mask" user "Board Geometry/Soldermask Bottom")
		(17 "Dwgs.User" user "User.Drawings")
		(19 "Cmts.User" user "User.Comments")
		(21 "Eco1.User" user "User.Eco1")
		(23 "Eco2.User" user "User.Eco2")
		(25 "Edge.Cuts" user "Board Geometry/Outline")
		(27 "Margin" user)
		(31 "F.CrtYd" user "Package Geometry/Place Bound Top")
		(29 "B.CrtYd" user "Package Geometry/Place Bound Bottom")
		(35 "F.Fab" user "Ref Des/Assembly Top")
		(33 "B.Fab" user "Ref Des/Assembly Bottom")
	)
	(footprint ""
		(layer "F.Cu")
		(at 170.299634 -423.870882 -90)
		(property "Reference" "U21"
			(at -0.392938 -3.18262 90)
			(unlocked yes)
			(layer "F.SilkS")
			(effects
				(font
					(size 0.7874 0.5842)
					(thickness 0.1524)
				)
				(justify left)
			)
		)
		(property "Value" ""
			(at 0 0 270)
			(layer "F.Fab")
			(effects
				(font
					(size 1.27 1.27)
				)
			)
		)
		(duplicate_pad_numbers_are_jumpers no)
		(fp_line
			(start -1.8288 2.500122)
			(end 1.8288 2.500122)
			(stroke
				(width 0.1524)
				(type default)
			)
			(layer "F.SilkS")
		)
		(fp_line
			(start 1.8288 2.500122)
			(end 1.8288 -2.500122)
			(stroke
				(width 0.1524)
				(type default)
			)
			(layer "F.SilkS")
		)
		(fp_line
			(start 0 -1.4224)
			(end -1.077722 -2.500122)
			(stroke
				(width 0.1524)
				(type default)
			)
			(layer "F.SilkS")
		)
		(fp_line
			(start -1.8288 -2.500122)
			(end -1.8288 2.500122)
			(stroke
				(width 0.1524)
				(type default)
			)
			(layer "F.SilkS")
		)
		(fp_line
			(start -1.077722 -2.500122)
			(end -1.8288 -2.500122)
			(stroke
				(width 0.1524)
				(type default)
			)
			(layer "F.SilkS")
		)
		(fp_line
			(start 1.077722 -2.500122)
			(end 0 -1.4224)
			(stroke
				(width 0.1524)
				(type default)
			)
			(layer "F.SilkS")
		)
		(fp_line
			(start 1.8288 -2.500122)
			(end 1.077722 -2.500122)
			(stroke
				(width 0.1524)
				(type default)
			)
			(layer "F.SilkS")
		)
		(fp_poly
			(pts
				(xy -4.51485 -2.535174) (xy -4.51485 -1.519174) (xy -3.49885 -2.027174)
			)
			(stroke
				(width 0)
				(type default)
			)
			(fill yes)
			(layer "F.SilkS")
		)
		(fp_line
			(start -1.999996 2.500122)
			(end 1.999996 2.500122)
			(stroke
				(width 0.1)
				(type default)
			)
			(layer "F.Fab")
		)
		(fp_line
			(start 1.999996 2.500122)
			(end 1.999996 -2.500122)
			(stroke
				(width 0.1)
				(type default)
			)
			(layer "F.Fab")
		)
		(fp_line
			(start -1.999996 -2.500122)
			(end -1.999996 2.500122)
			(stroke
				(width 0.1)
				(type default)
			)
			(layer "F.Fab")
		)
		(fp_line
			(start 1.999996 -2.500122)
			(end -1.999996 -2.500122)
			(stroke
				(width 0.1)
				(type default)
			)
			(layer "F.Fab")
		)
		(fp_poly
			(pts
				(xy -4.5085 -2.413) (xy -4.5085 -1.397) (xy -3.4925 -1.905)
			)
			(stroke
				(width 0)
				(type default)
			)
			(fill yes)
			(layer "F.Fab")
		)
		(pad "1" smd rect
			(at -2.599944 -1.905 180)
			(size 0.889 1.27)
			(layers "F.Cu" "F.Mask" "F.Paste")
			(net "Net_10833")
		)
		(pad "2" smd rect
			(at -2.599944 -0.635 180)
			(size 0.889 1.27)
			(layers "F.Cu" "F.Mask" "F.Paste")
			(net "Net_10832")
		)
		(pad "3" smd rect
			(at -2.599944 0.635 180)
			(size 0.889 1.27)
			(layers "F.Cu" "F.Mask" "F.Paste")
			(net "U21_E2")
		)
		(pad "4" smd rect
			(at -2.599944 1.905 180)
			(size 0.889 1.27)
			(layers "F.Cu" "F.Mask" "F.Paste")
			(net "GND")
		)
		(pad "5" smd rect
			(at 2.599944 1.905 180)
			(size 0.889 1.27)
			(layers "F.Cu" "F.Mask" "F.Paste")
			(net "SMB_RT_CPU1_P3_ROM_SDA")
		)
		(pad "6" smd rect
			(at 2.599944 0.635 180)
			(size 0.889 1.27)
			(layers "F.Cu" "F.Mask" "F.Paste")
			(net "SMB_RT_CPU1_P3_ROM_SCL")
		)
		(pad "7" smd rect
			(at 2.599944 -0.635 180)
			(size 0.889 1.27)
			(layers "F.Cu" "F.Mask" "F.Paste")
			(net "GND")
		)
		(pad "8" smd rect
			(at 2.599944 -1.905 180)
			(size 0.889 1.27)
			(layers "F.Cu" "F.Mask" "F.Paste")
			(net "P1V8_CPU1_RT_1D")
		)
	)
	(footprint ""
		(layer "F.Cu")
		(at 293.550086 -435.600094)
		(property "Reference" "H104"
			(at -7.357364 -3.906266 0)
			(unlocked yes)
			(layer "F.SilkS")
			(effects
				(font
					(size 0.7874 0.5842)
					(thickness 0.1524)
				)
				(justify left)
			)
		)
		(property "Value" ""
			(at 0 0 0)
			(layer "F.Fab")
			(effects
				(font
					(size 1.27 1.27)
				)
			)
		)
		(duplicate_pad_numbers_are_jumpers no)
		(pad "1" thru_hole circle
			(at 0 0)
			(size 10.0076 10.0076)
			(drill 5.6134)
			(layers "*.Cu" "*.Mask")
			(remove_unused_layers no)
			(net "GND")
			(clearance -1.9431)
		)
	)
	(footprint ""
		(layer "F.Cu")
		(at 214.613744 -23.304754 90)
		(property "Reference" "R1138"
			(at 0 0 90)
			(layer "F.SilkS")
			(hide yes)
			(effects
				(font
					(size 1.27 1.27)
				)
			)
		)
		(property "Value" ""
			(at 0 0 90)
			(layer "F.Fab")
			(effects
				(font
					(size 1.27 1.27)
				)
			)
		)
		(duplicate_pad_numbers_are_jumpers no)
		(fp_line
			(start 0.7874 -0.4064)
			(end 0.7874 0.4064)
			(stroke
				(width 0.1524)
				(type default)
			)
			(layer "F.SilkS")
		)
		(fp_line
			(start -0.7874 -0.4064)
			(end 0.7874 -0.4064)
			(stroke
				(width 0.1524)
				(type default)
			)
			(layer "F.SilkS")
		)
		(fp_line
			(start 0.7874 0.4064)
			(end -0.7874 0.4064)
			(stroke
				(width 0.1524)
				(type default)
			)
			(layer "F.SilkS")
		)
		(fp_line
			(start -0.7874 0.4064)
			(end -0.7874 -0.4064)
			(stroke
				(width 0.1524)
				(type default)
			)
			(layer "F.SilkS")
		)
		(fp_line
			(start -0.12065 -0.305054)
			(end -0.12065 -0.2794)
			(stroke
				(width 0.1)
				(type default)
			)
			(layer "F.Fab")
		)
		(fp_line
			(start -0.67945 -0.305054)
			(end -0.12065 -0.305054)
			(stroke
				(width 0.1)
				(type default)
			)
			(layer "F.Fab")
		)
		(fp_line
			(start 0.67945 -0.3048)
			(end 0.67945 0.3048)
			(stroke
				(width 0.1)
				(type default)
			)
			(layer "F.Fab")
		)
		(fp_line
			(start 0.12065 -0.3048)
			(end 0.67945 -0.3048)
			(stroke
				(width 0.1)
				(type default)
			)
			(layer "F.Fab")
		)
		(fp_line
			(start 0.12065 -0.2794)
			(end 0.12065 -0.3048)
			(stroke
				(width 0.1)
				(type default)
			)
			(layer "F.Fab")
		)
		(fp_line
			(start -0.12065 -0.2794)
			(end 0.12065 -0.2794)
			(stroke
				(width 0.1)
				(type default)
			)
			(layer "F.Fab")
		)
		(fp_line
			(start 0.120396 0.2794)
			(end -0.12065 0.2794)
			(stroke
				(width 0.1)
				(type default)
			)
			(layer "F.Fab")
		)
		(fp_line
			(start -0.12065 0.2794)
			(end -0.12065 0.3048)
			(stroke
				(width 0.1)
				(type default)
			)
			(layer "F.Fab")
		)
		(fp_line
			(start 0.67945 0.3048)
			(end 0.120396 0.3048)
			(stroke
				(width 0.1)
				(type default)
			)
			(layer "F.Fab")
		)
		(fp_line
			(start 0.120396 0.3048)
			(end 0.120396 0.2794)
			(stroke
				(width 0.1)
				(type default)
			)
			(layer "F.Fab")
		)
		(fp_line
			(start -0.12065 0.3048)
			(end -0.67945 0.3048)
			(stroke
				(width 0.1)
				(type default)
			)
			(layer "F.Fab")
		)
		(fp_line
			(start -0.67945 0.3048)
			(end -0.67945 -0.305054)
			(stroke
				(width 0.1)
				(type default)
			)
			(layer "F.Fab")
		)
		(pad "1" smd circle
			(at -0.40005 0 90)
			(size 0 0)
			(layers "F.Cu" "F.Mask" "F.Paste")
			(net "P3V3_AUX")
		)
		(pad "2" smd circle
			(at 0.40005 0 90)
			(size 0 0)
			(layers "F.Cu" "F.Mask" "F.Paste")
			(net "CLK_50M_EN")
		)
	)
)
